(kicad_pcb
	(version 20260206)
	(generator "pcbnew")
	(generator_version "10.0")
	(general
		(thickness 1.6)
		(legacy_teardrops no)
	)
	(paper "A4")
	(title_block
		(title "04192023_DAF0TMB3IC0_F0TG_MB_C_brd_V02_OCP.brd")
		(comment 1 "Grand Teton / footprints 7405-7411 of 8354")
	)
	(layers
		(0 "F.Cu" signal "TOP")
		(4 "In1.Cu" signal "GND")
		(6 "In2.Cu" signal "IN1")
		(8 "In3.Cu" signal "GND1")
		(10 "In4.Cu" signal "IN2")
		(12 "In5.Cu" signal "GND2")
		(14 "In6.Cu" signal "IN3")
		(16 "In7.Cu" signal "GND3")
		(18 "In8.Cu" signal "VCC")
		(20 "In9.Cu" signal "VCC1")
		(22 "In10.Cu" signal "GND4")
		(24 "In11.Cu" signal "IN4")
		(26 "In12.Cu" signal "GND5")
		(28 "In13.Cu" signal "IN5")
		(30 "In14.Cu" signal "GND6")
		(32 "In15.Cu" signal "IN6")
		(34 "In16.Cu" signal "GND7")
		(2 "B.Cu" signal "BOTTOM")
		(9 "F.Adhes" user "F.Adhesive")
		(11 "B.Adhes" user "B.Adhesive")
		(13 "F.Paste" user "Package Geometry/Pastemask Top")
		(15 "B.Paste" user "Package Geometry/Pastemask Bottom")
		(5 "F.SilkS" user "Ref Des/Silkscreen Top")
		(7 "B.SilkS" user "Ref Des/Silkscreen Bottom")
		(1 "F.Mask" user "Board Geometry/Soldermask Top")
		(3 "B.Mask" user "Board Geometry/Soldermask Bottom")
		(17 "Dwgs.User" user "User.Drawings")
		(19 "Cmts.User" user "User.Comments")
		(21 "Eco1.User" user "User.Eco1")
		(23 "Eco2.User" user "User.Eco2")
		(25 "Edge.Cuts" user "Board Geometry/Outline")
		(27 "Margin" user)
		(31 "F.CrtYd" user "Package Geometry/Place Bound Top")
		(29 "B.CrtYd" user "Package Geometry/Place Bound Bottom")
		(35 "F.Fab" user "Ref Des/Assembly Top")
		(33 "B.Fab" user "Ref Des/Assembly Bottom")
	)
	(footprint ""
		(layer "B.Cu")
		(at 111.800386 -249.876564 90)
		(property "Reference" "C2332"
			(at 0 0 90)
			(layer "B.SilkS")
			(hide yes)
			(effects
				(font
					(size 1.27 1.27)
				)
				(justify mirror)
			)
		)
		(property "Value" ""
			(at 0 0 90)
			(layer "B.Fab")
			(effects
				(font
					(size 1.27 1.27)
				)
				(justify mirror)
			)
		)
		(duplicate_pad_numbers_are_jumpers no)
		(fp_line
			(start 0.7874 -0.4064)
			(end -0.7874 -0.4064)
			(stroke
				(width 0.1524)
				(type default)
			)
			(layer "B.SilkS")
		)
		(fp_line
			(start -0.7874 -0.4064)
			(end -0.7874 0.4064)
			(stroke
				(width 0.1524)
				(type default)
			)
			(layer "B.SilkS")
		)
		(fp_line
			(start 0.7874 0.4064)
			(end 0.7874 -0.4064)
			(stroke
				(width 0.1524)
				(type default)
			)
			(layer "B.SilkS")
		)
		(fp_line
			(start -0.7874 0.4064)
			(end 0.7874 0.4064)
			(stroke
				(width 0.1524)
				(type default)
			)
			(layer "B.SilkS")
		)
		(fp_line
			(start 0.67945 -0.305054)
			(end 0.12065 -0.305054)
			(stroke
				(width 0.1)
				(type default)
			)
			(layer "B.Fab")
		)
		(fp_line
			(start 0.12065 -0.305054)
			(end 0.12065 -0.2794)
			(stroke
				(width 0.1)
				(type default)
			)
			(layer "B.Fab")
		)
		(fp_line
			(start -0.12065 -0.3048)
			(end -0.67945 -0.3048)
			(stroke
				(width 0.1)
				(type default)
			)
			(layer "B.Fab")
		)
		(fp_line
			(start -0.67945 -0.3048)
			(end -0.67945 0.3048)
			(stroke
				(width 0.1)
				(type default)
			)
			(layer "B.Fab")
		)
		(fp_line
			(start 0.12065 -0.2794)
			(end -0.12065 -0.2794)
			(stroke
				(width 0.1)
				(type default)
			)
			(layer "B.Fab")
		)
		(fp_line
			(start -0.12065 -0.2794)
			(end -0.12065 -0.3048)
			(stroke
				(width 0.1)
				(type default)
			)
			(layer "B.Fab")
		)
		(fp_line
			(start 0.12065 0.2794)
			(end 0.12065 0.3048)
			(stroke
				(width 0.1)
				(type default)
			)
			(layer "B.Fab")
		)
		(fp_line
			(start -0.120396 0.2794)
			(end 0.12065 0.2794)
			(stroke
				(width 0.1)
				(type default)
			)
			(layer "B.Fab")
		)
		(fp_line
			(start 0.67945 0.3048)
			(end 0.67945 -0.305054)
			(stroke
				(width 0.1)
				(type default)
			)
			(layer "B.Fab")
		)
		(fp_line
			(start 0.12065 0.3048)
			(end 0.67945 0.3048)
			(stroke
				(width 0.1)
				(type default)
			)
			(layer "B.Fab")
		)
		(fp_line
			(start -0.120396 0.3048)
			(end -0.120396 0.2794)
			(stroke
				(width 0.1)
				(type default)
			)
			(layer "B.Fab")
		)
		(fp_line
			(start -0.67945 0.3048)
			(end -0.120396 0.3048)
			(stroke
				(width 0.1)
				(type default)
			)
			(layer "B.Fab")
		)
		(pad "1" smd circle
			(at 0.40005 0 270)
			(size 0 0)
			(layers "B.Cu" "B.Mask" "B.Paste")
			(net "PVDDCR_CPU0_P1")
		)
		(pad "2" smd circle
			(at -0.40005 0 270)
			(size 0 0)
			(layers "B.Cu" "B.Mask" "B.Paste")
			(net "GND")
		)
	)
	(footprint ""
		(layer "B.Cu")
		(at 62.53988 -8.981948 90)
		(property "Reference" "C1837"
			(at 0 0 90)
			(layer "B.SilkS")
			(hide yes)
			(effects
				(font
					(size 1.27 1.27)
				)
				(justify mirror)
			)
		)
		(property "Value" ""
			(at 0 0 90)
			(layer "B.Fab")
			(effects
				(font
					(size 1.27 1.27)
				)
				(justify mirror)
			)
		)
		(duplicate_pad_numbers_are_jumpers no)
		(fp_line
			(start 0.7874 -0.4064)
			(end -0.7874 -0.4064)
			(stroke
				(width 0.1524)
				(type default)
			)
			(layer "B.SilkS")
		)
		(fp_line
			(start -0.7874 -0.4064)
			(end -0.7874 0.4064)
			(stroke
				(width 0.1524)
				(type default)
			)
			(layer "B.SilkS")
		)
		(fp_line
			(start 0.7874 0.4064)
			(end 0.7874 -0.4064)
			(stroke
				(width 0.1524)
				(type default)
			)
			(layer "B.SilkS")
		)
		(fp_line
			(start -0.7874 0.4064)
			(end 0.7874 0.4064)
			(stroke
				(width 0.1524)
				(type default)
			)
			(layer "B.SilkS")
		)
		(fp_line
			(start 0.67945 -0.305054)
			(end 0.12065 -0.305054)
			(stroke
				(width 0.1)
				(type default)
			)
			(layer "B.Fab")
		)
		(fp_line
			(start 0.12065 -0.305054)
			(end 0.12065 -0.2794)
			(stroke
				(width 0.1)
				(type default)
			)
			(layer "B.Fab")
		)
		(fp_line
			(start -0.12065 -0.3048)
			(end -0.67945 -0.3048)
			(stroke
				(width 0.1)
				(type default)
			)
			(layer "B.Fab")
		)
		(fp_line
			(start -0.67945 -0.3048)
			(end -0.67945 0.3048)
			(stroke
				(width 0.1)
				(type default)
			)
			(layer "B.Fab")
		)
		(fp_line
			(start 0.12065 -0.2794)
			(end -0.12065 -0.2794)
			(stroke
				(width 0.1)
				(type default)
			)
			(layer "B.Fab")
		)
		(fp_line
			(start -0.12065 -0.2794)
			(end -0.12065 -0.3048)
			(stroke
				(width 0.1)
				(type default)
			)
			(layer "B.Fab")
		)
		(fp_line
			(start 0.12065 0.2794)
			(end 0.12065 0.3048)
			(stroke
				(width 0.1)
				(type default)
			)
			(layer "B.Fab")
		)
		(fp_line
			(start -0.120396 0.2794)
			(end 0.12065 0.2794)
			(stroke
				(width 0.1)
				(type default)
			)
			(layer "B.Fab")
		)
		(fp_line
			(start 0.67945 0.3048)
			(end 0.67945 -0.305054)
			(stroke
				(width 0.1)
				(type default)
			)
			(layer "B.Fab")
		)
		(fp_line
			(start 0.12065 0.3048)
			(end 0.67945 0.3048)
			(stroke
				(width 0.1)
				(type default)
			)
			(layer "B.Fab")
		)
		(fp_line
			(start -0.120396 0.3048)
			(end -0.120396 0.2794)
			(stroke
				(width 0.1)
				(type default)
			)
			(layer "B.Fab")
		)
		(fp_line
			(start -0.67945 0.3048)
			(end -0.120396 0.3048)
			(stroke
				(width 0.1)
				(type default)
			)
			(layer "B.Fab")
		)
		(pad "1" smd circle
			(at 0.40005 0 270)
			(size 0 0)
			(layers "B.Cu" "B.Mask" "B.Paste")
			(net "P3V3_OCP_V3_2")
		)
		(pad "2" smd circle
			(at -0.40005 0 270)
			(size 0 0)
			(layers "B.Cu" "B.Mask" "B.Paste")
			(net "GND")
		)
	)
	(footprint ""
		(layer "B.Cu")
		(at 311.945782 -346.784168 90)
		(property "Reference" "PC119_4"
			(at 0 0 90)
			(layer "B.SilkS")
			(hide yes)
			(effects
				(font
					(size 1.27 1.27)
				)
				(justify mirror)
			)
		)
		(property "Value" ""
			(at 0 0 90)
			(layer "B.Fab")
			(effects
				(font
					(size 1.27 1.27)
				)
				(justify mirror)
			)
		)
		(duplicate_pad_numbers_are_jumpers no)
		(fp_line
			(start 1.524 -0.762)
			(end -1.524 -0.762)
			(stroke
				(width 0.1524)
				(type default)
			)
			(layer "B.SilkS")
		)
		(fp_line
			(start -1.524 -0.762)
			(end -1.524 0.762)
			(stroke
				(width 0.1524)
				(type default)
			)
			(layer "B.SilkS")
		)
		(fp_line
			(start 1.524 0.762)
			(end 1.524 -0.762)
			(stroke
				(width 0.1524)
				(type default)
			)
			(layer "B.SilkS")
		)
		(fp_line
			(start -1.524 0.762)
			(end 1.524 0.762)
			(stroke
				(width 0.1524)
				(type default)
			)
			(layer "B.SilkS")
		)
		(fp_line
			(start 1.1049 -0.724916)
			(end 1.1049 0.724916)
			(stroke
				(width 0.1)
				(type default)
			)
			(layer "B.Fab")
		)
		(fp_line
			(start -1.1049 -0.724916)
			(end 1.1049 -0.724916)
			(stroke
				(width 0.1)
				(type default)
			)
			(layer "B.Fab")
		)
		(fp_line
			(start 1.1049 0.724916)
			(end -1.1049 0.724916)
			(stroke
				(width 0.1)
				(type default)
			)
			(layer "B.Fab")
		)
		(fp_line
			(start -1.1049 0.724916)
			(end -1.1049 -0.724916)
			(stroke
				(width 0.1)
				(type default)
			)
			(layer "B.Fab")
		)
		(pad "1" smd rect
			(at 0.889 0 90)
			(size 1.016 1.27)
			(layers "B.Cu" "B.Mask" "B.Paste")
			(net "SW_P12V_AUX_PVDDCR_CPU1_P0_FLT")
		)
		(pad "2" smd rect
			(at -0.889 0 90)
			(size 1.016 1.27)
			(layers "B.Cu" "B.Mask" "B.Paste")
			(net "GND")
		)
	)
	(footprint ""
		(layer "B.Cu")
		(at 205.388972 -72.214994 180)
		(property "Reference" "R3215"
			(at 0 0 0)
			(layer "B.SilkS")
			(hide yes)
			(effects
				(font
					(size 1.27 1.27)
				)
				(justify mirror)
			)
		)
		(property "Value" ""
			(at 0 0 0)
			(layer "B.Fab")
			(effects
				(font
					(size 1.27 1.27)
				)
				(justify mirror)
			)
		)
		(duplicate_pad_numbers_are_jumpers no)
		(fp_line
			(start 0.7874 0.4064)
			(end 0.7874 -0.4064)
			(stroke
				(width 0.1524)
				(type default)
			)
			(layer "B.SilkS")
		)
		(fp_line
			(start 0.7874 -0.4064)
			(end -0.7874 -0.4064)
			(stroke
				(width 0.1524)
				(type default)
			)
			(layer "B.SilkS")
		)
		(fp_line
			(start -0.7874 0.4064)
			(end 0.7874 0.4064)
			(stroke
				(width 0.1524)
				(type default)
			)
			(layer "B.SilkS")
		)
		(fp_line
			(start -0.7874 -0.4064)
			(end -0.7874 0.4064)
			(stroke
				(width 0.1524)
				(type default)
			)
			(layer "B.SilkS")
		)
		(fp_line
			(start 0.67945 0.3048)
			(end 0.67945 -0.305054)
			(stroke
				(width 0.1)
				(type default)
			)
			(layer "B.Fab")
		)
		(fp_line
			(start 0.67945 -0.305054)
			(end 0.12065 -0.305054)
			(stroke
				(width 0.1)
				(type default)
			)
			(layer "B.Fab")
		)
		(fp_line
			(start 0.12065 0.3048)
			(end 0.67945 0.3048)
			(stroke
				(width 0.1)
				(type default)
			)
			(layer "B.Fab")
		)
		(fp_line
			(start 0.12065 0.2794)
			(end 0.12065 0.3048)
			(stroke
				(width 0.1)
				(type default)
			)
			(layer "B.Fab")
		)
		(fp_line
			(start 0.12065 -0.2794)
			(end -0.12065 -0.2794)
			(stroke
				(width 0.1)
				(type default)
			)
			(layer "B.Fab")
		)
		(fp_line
			(start 0.12065 -0.305054)
			(end 0.12065 -0.2794)
			(stroke
				(width 0.1)
				(type default)
			)
			(layer "B.Fab")
		)
		(fp_line
			(start -0.120396 0.3048)
			(end -0.120396 0.2794)
			(stroke
				(width 0.1)
				(type default)
			)
			(layer "B.Fab")
		)
		(fp_line
			(start -0.120396 0.2794)
			(end 0.12065 0.2794)
			(stroke
				(width 0.1)
				(type default)
			)
			(layer "B.Fab")
		)
		(fp_line
			(start -0.12065 -0.2794)
			(end -0.12065 -0.3048)
			(stroke
				(width 0.1)
				(type default)
			)
			(layer "B.Fab")
		)
		(fp_line
			(start -0.12065 -0.3048)
			(end -0.67945 -0.3048)
			(stroke
				(width 0.1)
				(type default)
			)
			(layer "B.Fab")
		)
		(fp_line
			(start -0.67945 0.3048)
			(end -0.120396 0.3048)
			(stroke
				(width 0.1)
				(type default)
			)
			(layer "B.Fab")
		)
		(fp_line
			(start -0.67945 -0.3048)
			(end -0.67945 0.3048)
			(stroke
				(width 0.1)
				(type default)
			)
			(layer "B.Fab")
		)
		(pad "1" smd circle
			(at 0.40005 0)
			(size 0 0)
			(layers "B.Cu" "B.Mask" "B.Paste")
			(net "NCSI_BMC_TXD1_R1")
		)
		(pad "2" smd circle
			(at -0.40005 0)
			(size 0 0)
			(layers "B.Cu" "B.Mask" "B.Paste")
			(net "RMII_BMC_OCP_TXD_1")
		)
	)
	(footprint ""
		(layer "B.Cu")
		(at 402.800566 -393.88288 -90)
		(property "Reference" "C779"
			(at 0 0 90)
			(layer "B.SilkS")
			(hide yes)
			(effects
				(font
					(size 1.27 1.27)
				)
				(justify mirror)
			)
		)
		(property "Value" ""
			(at 0 0 90)
			(layer "B.Fab")
			(effects
				(font
					(size 1.27 1.27)
				)
				(justify mirror)
			)
		)
		(duplicate_pad_numbers_are_jumpers no)
		(fp_line
			(start -0.299974 0.150114)
			(end 0.299974 0.150114)
			(stroke
				(width 0.1)
				(type default)
			)
			(layer "B.Fab")
		)
		(fp_line
			(start 0.299974 0.150114)
			(end 0.299974 -0.150114)
			(stroke
				(width 0.1)
				(type default)
			)
			(layer "B.Fab")
		)
		(fp_line
			(start -0.299974 -0.150114)
			(end -0.299974 0.150114)
			(stroke
				(width 0.1)
				(type default)
			)
			(layer "B.Fab")
		)
		(fp_line
			(start 0.299974 -0.150114)
			(end -0.299974 -0.150114)
			(stroke
				(width 0.1)
				(type default)
			)
			(layer "B.Fab")
		)
		(pad "1" smd rect
			(at 0.2667 0 90)
			(size 0.3048 0.381)
			(layers "B.Cu" "B.Mask" "B.Paste")
			(net "P0V9_CPU0_RT2_2A")
		)
		(pad "2" smd rect
			(at -0.2667 0 90)
			(size 0.3048 0.381)
			(layers "B.Cu" "B.Mask" "B.Paste")
			(net "GND")
		)
	)
	(footprint ""
		(layer "B.Cu")
		(at 171.20235 -120.233948 180)
		(property "Reference" "R6117"
			(at 0 0 0)
			(layer "B.SilkS")
			(hide yes)
			(effects
				(font
					(size 1.27 1.27)
				)
				(justify mirror)
			)
		)
		(property "Value" ""
			(at 0 0 0)
			(layer "B.Fab")
			(effects
				(font
					(size 1.27 1.27)
				)
				(justify mirror)
			)
		)
		(duplicate_pad_numbers_are_jumpers no)
		(fp_line
			(start 0.7874 0.4064)
			(end 0.7874 -0.4064)
			(stroke
				(width 0.1524)
				(type default)
			)
			(layer "B.SilkS")
		)
		(fp_line
			(start 0.7874 -0.4064)
			(end -0.7874 -0.4064)
			(stroke
				(width 0.1524)
				(type default)
			)
			(layer "B.SilkS")
		)
		(fp_line
			(start -0.7874 0.4064)
			(end 0.7874 0.4064)
			(stroke
				(width 0.1524)
				(type default)
			)
			(layer "B.SilkS")
		)
		(fp_line
			(start -0.7874 -0.4064)
			(end -0.7874 0.4064)
			(stroke
				(width 0.1524)
				(type default)
			)
			(layer "B.SilkS")
		)
		(fp_line
			(start 0.67945 0.3048)
			(end 0.67945 -0.305054)
			(stroke
				(width 0.1)
				(type default)
			)
			(layer "B.Fab")
		)
		(fp_line
			(start 0.67945 -0.305054)
			(end 0.12065 -0.305054)
			(stroke
				(width 0.1)
				(type default)
			)
			(layer "B.Fab")
		)
		(fp_line
			(start 0.12065 0.3048)
			(end 0.67945 0.3048)
			(stroke
				(width 0.1)
				(type default)
			)
			(layer "B.Fab")
		)
		(fp_line
			(start 0.12065 0.2794)
			(end 0.12065 0.3048)
			(stroke
				(width 0.1)
				(type default)
			)
			(layer "B.Fab")
		)
		(fp_line
			(start 0.12065 -0.2794)
			(end -0.12065 -0.2794)
			(stroke
				(width 0.1)
				(type default)
			)
			(layer "B.Fab")
		)
		(fp_line
			(start 0.12065 -0.305054)
			(end 0.12065 -0.2794)
			(stroke
				(width 0.1)
				(type default)
			)
			(layer "B.Fab")
		)
		(fp_line
			(start -0.120396 0.3048)
			(end -0.120396 0.2794)
			(stroke
				(width 0.1)
				(type default)
			)
			(layer "B.Fab")
		)
		(fp_line
			(start -0.120396 0.2794)
			(end 0.12065 0.2794)
			(stroke
				(width 0.1)
				(type default)
			)
			(layer "B.Fab")
		)
		(fp_line
			(start -0.12065 -0.2794)
			(end -0.12065 -0.3048)
			(stroke
				(width 0.1)
				(type default)
			)
			(layer "B.Fab")
		)
		(fp_line
			(start -0.12065 -0.3048)
			(end -0.67945 -0.3048)
			(stroke
				(width 0.1)
				(type default)
			)
			(layer "B.Fab")
		)
		(fp_line
			(start -0.67945 0.3048)
			(end -0.120396 0.3048)
			(stroke
				(width 0.1)
				(type default)
			)
			(layer "B.Fab")
		)
		(fp_line
			(start -0.67945 -0.3048)
			(end -0.67945 0.3048)
			(stroke
				(width 0.1)
				(type default)
			)
			(layer "B.Fab")
		)
		(pad "1" smd circle
			(at 0.40005 0)
			(size 0 0)
			(layers "B.Cu" "B.Mask" "B.Paste")
			(net "HP_LVC3_OCP_V3_2_PRSNT2_PLD_N")
		)
		(pad "2" smd circle
			(at -0.40005 0)
			(size 0 0)
			(layers "B.Cu" "B.Mask" "B.Paste")
			(net "PRSNT_OCP_V3_2_N")
		)
	)
	(footprint ""
		(layer "B.Cu")
		(at 286.004 -425.958 -90)
		(property "Reference" "R2670"
			(at 0 0 90)
			(layer "B.SilkS")
			(hide yes)
			(effects
				(font
					(size 1.27 1.27)
				)
				(justify mirror)
			)
		)
		(property "Value" ""
			(at 0 0 90)
			(layer "B.Fab")
			(effects
				(font
					(size 1.27 1.27)
				)
				(justify mirror)
			)
		)
		(duplicate_pad_numbers_are_jumpers no)
		(fp_line
			(start -0.7874 0.4064)
			(end 0.7874 0.4064)
			(stroke
				(width 0.1524)
				(type default)
			)
			(layer "B.SilkS")
		)
		(fp_line
			(start 0.7874 0.4064)
			(end 0.7874 -0.4064)
			(stroke
				(width 0.1524)
				(type default)
			)
			(layer "B.SilkS")
		)
		(fp_line
			(start -0.7874 -0.4064)
			(end -0.7874 0.4064)
			(stroke
				(width 0.1524)
				(type default)
			)
			(layer "B.SilkS")
		)
		(fp_line
			(start 0.7874 -0.4064)
			(end -0.7874 -0.4064)
			(stroke
				(width 0.1524)
				(type default)
			)
			(layer "B.SilkS")
		)
		(fp_line
			(start -0.67945 0.3048)
			(end -0.120396 0.3048)
			(stroke
				(width 0.1)
				(type default)
			)
			(layer "B.Fab")
		)
		(fp_line
			(start -0.120396 0.3048)
			(end -0.120396 0.2794)
			(stroke
				(width 0.1)
				(type default)
			)
			(layer "B.Fab")
		)
		(fp_line
			(start 0.12065 0.3048)
			(end 0.67945 0.3048)
			(stroke
				(width 0.1)
				(type default)
			)
			(layer "B.Fab")
		)
		(fp_line
			(start 0.67945 0.3048)
			(end 0.67945 -0.305054)
			(stroke
				(width 0.1)
				(type default)
			)
			(layer "B.Fab")
		)
		(fp_line
			(start -0.120396 0.2794)
			(end 0.12065 0.2794)
			(stroke
				(width 0.1)
				(type default)
			)
			(layer "B.Fab")
		)
		(fp_line
			(start 0.12065 0.2794)
			(end 0.12065 0.3048)
			(stroke
				(width 0.1)
				(type default)
			)
			(layer "B.Fab")
		)
		(fp_line
			(start -0.12065 -0.2794)
			(end -0.12065 -0.3048)
			(stroke
				(width 0.1)
				(type default)
			)
			(layer "B.Fab")
		)
		(fp_line
			(start 0.12065 -0.2794)
			(end -0.12065 -0.2794)
			(stroke
				(width 0.1)
				(type default)
			)
			(layer "B.Fab")
		)
		(fp_line
			(start -0.67945 -0.3048)
			(end -0.67945 0.3048)
			(stroke
				(width 0.1)
				(type default)
			)
			(layer "B.Fab")
		)
		(fp_line
			(start -0.12065 -0.3048)
			(end -0.67945 -0.3048)
			(stroke
				(width 0.1)
				(type default)
			)
			(layer "B.Fab")
		)
		(fp_line
			(start 0.12065 -0.305054)
			(end 0.12065 -0.2794)
			(stroke
				(width 0.1)
				(type default)
			)
			(layer "B.Fab")
		)
		(fp_line
			(start 0.67945 -0.305054)
			(end 0.12065 -0.305054)
			(stroke
				(width 0.1)
				(type default)
			)
			(layer "B.Fab")
		)
		(pad "1" smd circle
			(at 0.40005 0 90)
			(size 0 0)
			(layers "B.Cu" "B.Mask" "B.Paste")
			(net "P3V3_AUX")
		)
		(pad "2" smd circle
			(at -0.40005 0 90)
			(size 0 0)
			(layers "B.Cu" "B.Mask" "B.Paste")
			(net "I3C_BMC_SWB_BUF_R_SCL")
		)
	)
)
